# BASEBOARD_FAB2 (Tioga Pass) — schematic netlist excerpt (pin names and nets, part order shuffled) for the footprints in the layout excerpt that follows; sources: Cadence DE-HDL packaged netlist, KiCad conversion of Wiwynn_Tioga_Pass_MB.brd

R4D27  RES  100.0K 1% CHIP  pkg 0402  page 201 : A = VR_FET_SW_P12V_STBY_PVCCIN_CPU0 ; B = VR_PVCCIN_CPU0_AVINSEN
R1D10  RES  10.0K 1% CHIP  pkg 0402  page 200 : A = P3V3_STBY ; B = A_HSC_LOW_GATE
R25W79  RES  10.0K 1% CHIP  pkg 0402  page 147 : A = P3V3_STBY ; B = RMII_SPRNGVLLE_BMC_PCH_RXD0

(kicad_pcb
	(version 20260206)
	(generator "pcbnew")
	(generator_version "10.0")
	(general
		(thickness 1.6)
		(legacy_teardrops no)
	)
	(paper "A4")
	(title_block
		(title "Wiwynn_Tioga_Pass_MB.brd")
		(comment 1 "Tioga Pass / footprints 299-301 of 4770")
	)
	(layers
		(0 "F.Cu" signal "TOP")
		(4 "In1.Cu" signal "L2GND")
		(6 "In2.Cu" signal "L3")
		(8 "In3.Cu" signal "L4GND")
		(10 "In4.Cu" signal "L5")
		(12 "In5.Cu" signal "L6GND")
		(14 "In6.Cu" signal "L7VCC")
		(16 "In7.Cu" signal "L8VCC")
		(18 "In8.Cu" signal "L9GND")
		(20 "In9.Cu" signal "L10")
		(22 "In10.Cu" signal "L11GND")
		(24 "In11.Cu" signal "L12")
		(26 "In12.Cu" signal "L13GND")
		(2 "B.Cu" signal "BOTTOM")
		(9 "F.Adhes" user "F.Adhesive")
		(11 "B.Adhes" user "B.Adhesive")
		(13 "F.Paste" user "Package Geometry/Pastemask Top")
		(15 "B.Paste" user "Package Geometry/Pastemask Bottom")
		(5 "F.SilkS" user "Ref Des/Silkscreen Top")
		(7 "B.SilkS" user "Ref Des/Silkscreen Bottom")
		(1 "F.Mask" user "Board Geometry/Soldermask Top")
		(3 "B.Mask" user "Board Geometry/Soldermask Bottom")
		(17 "Dwgs.User" user "User.Drawings")
		(19 "Cmts.User" user "User.Comments")
		(21 "Eco1.User" user "User.Eco1")
		(23 "Eco2.User" user "User.Eco2")
		(25 "Edge.Cuts" user "Board Geometry/Outline")
		(27 "Margin" user)
		(31 "F.CrtYd" user "Package Geometry/Place Bound Top")
		(29 "B.CrtYd" user "Package Geometry/Place Bound Bottom")
		(35 "F.Fab" user "Ref Des/Assembly Top")
		(33 "B.Fab" user "Ref Des/Assembly Bottom")
	)
	(footprint ""
		(layer "F.Cu")
		(at 182.3466 -79.4258)
		(property "Reference" "R4D27"
			(at 0 0 0)
			(layer "F.SilkS")
			(hide yes)
			(effects
				(font
					(size 1.27 1.27)
				)
			)
		)
		(property "Value" ""
			(at 0 0 0)
			(layer "F.Fab")
			(effects
				(font
					(size 1.27 1.27)
				)
			)
		)
		(duplicate_pad_numbers_are_jumpers no)
		(fp_rect
			(start -0.2794 -0.1016)
			(end 0.2794 0.9906)
			(stroke
				(width 0)
				(type default)
			)
			(fill no)
			(layer "F.CrtYd")
		)
		(fp_line
			(start -0.2794 -0.1016)
			(end -0.2794 0.9906)
			(stroke
				(width 0.1)
				(type default)
			)
			(layer "F.Fab")
		)
		(fp_line
			(start -0.2794 0.9906)
			(end 0.2794 0.9906)
			(stroke
				(width 0.1)
				(type default)
			)
			(layer "F.Fab")
		)
		(fp_line
			(start 0.2794 -0.1016)
			(end -0.2794 -0.1016)
			(stroke
				(width 0.1)
				(type default)
			)
			(layer "F.Fab")
		)
		(fp_line
			(start 0.2794 0.9906)
			(end 0.2794 -0.1016)
			(stroke
				(width 0.1)
				(type default)
			)
			(layer "F.Fab")
		)
		(pad "1" smd rect
			(at 0 0)
			(size 0.508 0.508)
			(layers "F.Cu" "F.Mask" "F.Paste")
			(net "VR_FET_SW_P12V_STBY_PVCCIN_CPU0")
		)
		(pad "2" smd rect
			(at 0 0.889)
			(size 0.508 0.508)
			(layers "F.Cu" "F.Mask" "F.Paste")
			(net "VR_PVCCIN_CPU0_AVINSEN")
		)
		(zone
			(layer "F.Cu")
			(hatch none 0.5)
			(connect_pads
				(clearance 0)
			)
			(min_thickness 0.25)
			(keepout
				(tracks allowed)
				(vias not_allowed)
				(pads allowed)
				(copperpour not_allowed)
				(footprints allowed)
			)
			(placement
				(enabled no)
				(sheetname "")
			)
			(fill
				(thermal_gap 0.5)
				(thermal_bridge_width 0.5)
				(island_removal_mode 0)
			)
			(polygon
				(pts
					(xy 182.0926 -79.1718) (xy 182.0926 -78.7908) (xy 182.6006 -78.7908) (xy 182.6006 -79.1718)
				)
			)
		)
		(zone
			(layer "F.Cu")
			(hatch none 0.5)
			(connect_pads
				(clearance 0)
			)
			(min_thickness 0.25)
			(keepout
				(tracks not_allowed)
				(vias allowed)
				(pads allowed)
				(copperpour not_allowed)
				(footprints allowed)
			)
			(placement
				(enabled no)
				(sheetname "")
			)
			(fill
				(thermal_gap 0.5)
				(thermal_bridge_width 0.5)
				(island_removal_mode 0)
			)
			(polygon
				(pts
					(xy 182.0926 -79.1718) (xy 182.0926 -78.7908) (xy 182.6006 -78.7908) (xy 182.6006 -79.1718)
				)
			)
		)
	)
	(footprint ""
		(layer "F.Cu")
		(at 406.107646 -22.171152 180)
		(property "Reference" "R25W79"
			(at -0.8382 -0.67818 180)
			(unlocked yes)
			(layer "F.SilkS")
			(effects
				(font
					(size 0.4064 0.254)
					(thickness 0.1524)
				)
				(justify left)
			)
		)
		(property "Value" ""
			(at 0 0 180)
			(layer "F.Fab")
			(effects
				(font
					(size 1.27 1.27)
				)
			)
		)
		(duplicate_pad_numbers_are_jumpers no)
		(fp_poly
			(pts
				(xy -0.2794 -0.1016) (xy 0.2794 -0.1016) (xy 0.2794 0.9906) (xy -0.2794 0.9906)
			)
			(stroke
				(width 0)
				(type default)
			)
			(fill no)
			(layer "F.CrtYd")
		)
		(fp_line
			(start 0.2794 0.9906)
			(end 0.2794 -0.1016)
			(stroke
				(width 0.1)
				(type default)
			)
			(layer "F.Fab")
		)
		(fp_line
			(start 0.2794 -0.1016)
			(end -0.2794 -0.1016)
			(stroke
				(width 0.1)
				(type default)
			)
			(layer "F.Fab")
		)
		(fp_line
			(start -0.2794 0.9906)
			(end 0.2794 0.9906)
			(stroke
				(width 0.1)
				(type default)
			)
			(layer "F.Fab")
		)
		(fp_line
			(start -0.2794 -0.1016)
			(end -0.2794 0.9906)
			(stroke
				(width 0.1)
				(type default)
			)
			(layer "F.Fab")
		)
		(pad "1" smd rect
			(at 0 0 180)
			(size 0.508 0.508)
			(layers "F.Cu" "F.Mask" "F.Paste")
			(net "P3V3_STBY")
		)
		(pad "2" smd rect
			(at 0 0.889 180)
			(size 0.508 0.508)
			(layers "F.Cu" "F.Mask" "F.Paste")
			(net "RMII_SPRNGVLLE_BMC_PCH_RXD0")
		)
		(zone
			(layer "F.Cu")
			(hatch none 0.5)
			(connect_pads
				(clearance 0)
			)
			(min_thickness 0.25)
			(keepout
				(tracks not_allowed)
				(vias allowed)
				(pads allowed)
				(copperpour not_allowed)
				(footprints allowed)
			)
			(placement
				(enabled no)
				(sheetname "")
			)
			(fill
				(thermal_gap 0.5)
				(thermal_bridge_width 0.5)
				(island_removal_mode 0)
			)
			(polygon
				(pts
					(xy 406.361646 -22.806152) (xy 405.853646 -22.806152) (xy 405.853646 -22.425152) (xy 406.361646 -22.425152)
				)
			)
		)
		(zone
			(layer "F.Cu")
			(hatch none 0.5)
			(connect_pads
				(clearance 0)
			)
			(min_thickness 0.25)
			(keepout
				(tracks allowed)
				(vias not_allowed)
				(pads allowed)
				(copperpour not_allowed)
				(footprints allowed)
			)
			(placement
				(enabled no)
				(sheetname "")
			)
			(fill
				(thermal_gap 0.5)
				(thermal_bridge_width 0.5)
				(island_removal_mode 0)
			)
			(polygon
				(pts
					(xy 406.361646 -22.425152) (xy 405.853646 -22.425152) (xy 405.853646 -22.806152) (xy 406.361646 -22.806152)
				)
			)
		)
	)
	(footprint ""
		(layer "F.Cu")
		(at 20.6121 -86.0298 90)
		(property "Reference" "R1D10"
			(at 0 0 90)
			(layer "F.SilkS")
			(hide yes)
			(effects
				(font
					(size 1.27 1.27)
				)
			)
		)
		(property "Value" ""
			(at 0 0 90)
			(layer "F.Fab")
			(effects
				(font
					(size 1.27 1.27)
				)
			)
		)
		(duplicate_pad_numbers_are_jumpers no)
		(fp_poly
			(pts
				(xy -0.2794 -0.1016) (xy 0.2794 -0.1016) (xy 0.2794 0.9906) (xy -0.2794 0.9906)
			)
			(stroke
				(width 0)
				(type default)
			)
			(fill no)
			(layer "F.CrtYd")
		)
		(fp_line
			(start 0.2794 -0.1016)
			(end -0.2794 -0.1016)
			(stroke
				(width 0.1)
				(type default)
			)
			(layer "F.Fab")
		)
		(fp_line
			(start -0.2794 -0.1016)
			(end -0.2794 0.9906)
			(stroke
				(width 0.1)
				(type default)
			)
			(layer "F.Fab")
		)
		(fp_line
			(start 0.2794 0.9906)
			(end 0.2794 -0.1016)
			(stroke
				(width 0.1)
				(type default)
			)
			(layer "F.Fab")
		)
		(fp_line
			(start -0.2794 0.9906)
			(end 0.2794 0.9906)
			(stroke
				(width 0.1)
				(type default)
			)
			(layer "F.Fab")
		)
		(pad "1" smd rect
			(at 0 0 90)
			(size 0.508 0.508)
			(layers "F.Cu" "F.Mask" "F.Paste")
			(net "P3V3_STBY")
		)
		(pad "2" smd rect
			(at 0 0.889 90)
			(size 0.508 0.508)
			(layers "F.Cu" "F.Mask" "F.Paste")
			(net "A_HSC_LOW_GATE")
		)
		(zone
			(layer "F.Cu")
			(hatch none 0.5)
			(connect_pads
				(clearance 0)
			)
			(min_thickness 0.25)
			(keepout
				(tracks allowed)
				(vias not_allowed)
				(pads allowed)
				(copperpour not_allowed)
				(footprints allowed)
			)
			(placement
				(enabled no)
				(sheetname "")
			)
			(fill
				(thermal_gap 0.5)
				(thermal_bridge_width 0.5)
				(island_removal_mode 0)
			)
			(polygon
				(pts
					(xy 20.8661 -85.7758) (xy 20.8661 -86.2838) (xy 21.2471 -86.2838) (xy 21.2471 -85.7758)
				)
			)
		)
		(zone
			(layer "F.Cu")
			(hatch none 0.5)
			(connect_pads
				(clearance 0)
			)
			(min_thickness 0.25)
			(keepout
				(tracks not_allowed)
				(vias allowed)
				(pads allowed)
				(copperpour not_allowed)
				(footprints allowed)
			)
			(placement
				(enabled no)
				(sheetname "")
			)
			(fill
				(thermal_gap 0.5)
				(thermal_bridge_width 0.5)
				(island_removal_mode 0)
			)
			(polygon
				(pts
					(xy 21.2471 -85.7758) (xy 21.2471 -86.2838) (xy 20.8661 -86.2838) (xy 20.8661 -85.7758)
				)
			)
		)
	)
)
